(kicad_pcb
	(version 20260206)
	(generator "pcbnew")
	(generator_version "10.0")
	(general
		(thickness 1.6)
		(legacy_teardrops no)
	)
	(paper "A4")
	(title_block
		(title "04192023_DAF0TMB3IC0_F0TG_MB_C_brd_V02_OCP.brd")
		(comment 1 "Grand Teton / footprints 2560-2565 of 8354")
	)
	(layers
		(0 "F.Cu" signal "TOP")
		(4 "In1.Cu" signal "GND")
		(6 "In2.Cu" signal "IN1")
		(8 "In3.Cu" signal "GND1")
		(10 "In4.Cu" signal "IN2")
		(12 "In5.Cu" signal "GND2")
		(14 "In6.Cu" signal "IN3")
		(16 "In7.Cu" signal "GND3")
		(18 "In8.Cu" signal "VCC")
		(20 "In9.Cu" signal "VCC1")
		(22 "In10.Cu" signal "GND4")
		(24 "In11.Cu" signal "IN4")
		(26 "In12.Cu" signal "GND5")
		(28 "In13.Cu" signal "IN5")
		(30 "In14.Cu" signal "GND6")
		(32 "In15.Cu" signal "IN6")
		(34 "In16.Cu" signal "GND7")
		(2 "B.Cu" signal "BOTTOM")
		(9 "F.Adhes" user "F.Adhesive")
		(11 "B.Adhes" user "B.Adhesive")
		(13 "F.Paste" user "Package Geometry/Pastemask Top")
		(15 "B.Paste" user "Package Geometry/Pastemask Bottom")
		(5 "F.SilkS" user "Ref Des/Silkscreen Top")
		(7 "B.SilkS" user "Ref Des/Silkscreen Bottom")
		(1 "F.Mask" user "Board Geometry/Soldermask Top")
		(3 "B.Mask" user "Board Geometry/Soldermask Bottom")
		(17 "Dwgs.User" user "User.Drawings")
		(19 "Cmts.User" user "User.Comments")
		(21 "Eco1.User" user "User.Eco1")
		(23 "Eco2.User" user "User.Eco2")
		(25 "Edge.Cuts" user "Board Geometry/Outline")
		(27 "Margin" user)
		(31 "F.CrtYd" user "Package Geometry/Place Bound Top")
		(29 "B.CrtYd" user "Package Geometry/Place Bound Bottom")
		(35 "F.Fab" user "Ref Des/Assembly Top")
		(33 "B.Fab" user "Ref Des/Assembly Bottom")
	)
	(footprint ""
		(layer "F.Cu")
		(at 391.290556 -73.359264 180)
		(property "Reference" "R1327"
			(at 0 0 180)
			(layer "F.SilkS")
			(hide yes)
			(effects
				(font
					(size 1.27 1.27)
				)
			)
		)
		(property "Value" ""
			(at 0 0 180)
			(layer "F.Fab")
			(effects
				(font
					(size 1.27 1.27)
				)
			)
		)
		(duplicate_pad_numbers_are_jumpers no)
		(fp_line
			(start 0.7874 0.4064)
			(end -0.7874 0.4064)
			(stroke
				(width 0.1524)
				(type default)
			)
			(layer "F.SilkS")
		)
		(fp_line
			(start 0.7874 -0.4064)
			(end 0.7874 0.4064)
			(stroke
				(width 0.1524)
				(type default)
			)
			(layer "F.SilkS")
		)
		(fp_line
			(start -0.7874 0.4064)
			(end -0.7874 -0.4064)
			(stroke
				(width 0.1524)
				(type default)
			)
			(layer "F.SilkS")
		)
		(fp_line
			(start -0.7874 -0.4064)
			(end 0.7874 -0.4064)
			(stroke
				(width 0.1524)
				(type default)
			)
			(layer "F.SilkS")
		)
		(fp_line
			(start 0.67945 0.3048)
			(end 0.120396 0.3048)
			(stroke
				(width 0.1)
				(type default)
			)
			(layer "F.Fab")
		)
		(fp_line
			(start 0.67945 -0.3048)
			(end 0.67945 0.3048)
			(stroke
				(width 0.1)
				(type default)
			)
			(layer "F.Fab")
		)
		(fp_line
			(start 0.12065 -0.2794)
			(end 0.12065 -0.3048)
			(stroke
				(width 0.1)
				(type default)
			)
			(layer "F.Fab")
		)
		(fp_line
			(start 0.12065 -0.3048)
			(end 0.67945 -0.3048)
			(stroke
				(width 0.1)
				(type default)
			)
			(layer "F.Fab")
		)
		(fp_line
			(start 0.120396 0.3048)
			(end 0.120396 0.2794)
			(stroke
				(width 0.1)
				(type default)
			)
			(layer "F.Fab")
		)
		(fp_line
			(start 0.120396 0.2794)
			(end -0.12065 0.2794)
			(stroke
				(width 0.1)
				(type default)
			)
			(layer "F.Fab")
		)
		(fp_line
			(start -0.12065 0.3048)
			(end -0.67945 0.3048)
			(stroke
				(width 0.1)
				(type default)
			)
			(layer "F.Fab")
		)
		(fp_line
			(start -0.12065 0.2794)
			(end -0.12065 0.3048)
			(stroke
				(width 0.1)
				(type default)
			)
			(layer "F.Fab")
		)
		(fp_line
			(start -0.12065 -0.2794)
			(end 0.12065 -0.2794)
			(stroke
				(width 0.1)
				(type default)
			)
			(layer "F.Fab")
		)
		(fp_line
			(start -0.12065 -0.305054)
			(end -0.12065 -0.2794)
			(stroke
				(width 0.1)
				(type default)
			)
			(layer "F.Fab")
		)
		(fp_line
			(start -0.67945 0.3048)
			(end -0.67945 -0.305054)
			(stroke
				(width 0.1)
				(type default)
			)
			(layer "F.Fab")
		)
		(fp_line
			(start -0.67945 -0.305054)
			(end -0.12065 -0.305054)
			(stroke
				(width 0.1)
				(type default)
			)
			(layer "F.Fab")
		)
		(pad "1" smd circle
			(at -0.40005 0 180)
			(size 0 0)
			(layers "F.Cu" "F.Mask" "F.Paste")
			(net "P3V3_AUX")
		)
		(pad "2" smd circle
			(at 0.40005 0 180)
			(size 0 0)
			(layers "F.Cu" "F.Mask" "F.Paste")
			(net "OCP_SFF_P3V3_P12V_ADC_R_ALERT")
		)
	)
	(footprint ""
		(layer "F.Cu")
		(at 298.050966 -22.747224)
		(property "Reference" "C193"
			(at 0 0 0)
			(layer "F.SilkS")
			(hide yes)
			(effects
				(font
					(size 1.27 1.27)
				)
			)
		)
		(property "Value" ""
			(at 0 0 0)
			(layer "F.Fab")
			(effects
				(font
					(size 1.27 1.27)
				)
			)
		)
		(duplicate_pad_numbers_are_jumpers no)
		(fp_line
			(start -0.7874 -0.4064)
			(end 0.7874 -0.4064)
			(stroke
				(width 0.1524)
				(type default)
			)
			(layer "F.SilkS")
		)
		(fp_line
			(start -0.7874 0.4064)
			(end -0.7874 -0.4064)
			(stroke
				(width 0.1524)
				(type default)
			)
			(layer "F.SilkS")
		)
		(fp_line
			(start 0.7874 -0.4064)
			(end 0.7874 0.4064)
			(stroke
				(width 0.1524)
				(type default)
			)
			(layer "F.SilkS")
		)
		(fp_line
			(start 0.7874 0.4064)
			(end -0.7874 0.4064)
			(stroke
				(width 0.1524)
				(type default)
			)
			(layer "F.SilkS")
		)
		(fp_line
			(start -0.67945 -0.305054)
			(end -0.12065 -0.305054)
			(stroke
				(width 0.1)
				(type default)
			)
			(layer "F.Fab")
		)
		(fp_line
			(start -0.67945 0.3048)
			(end -0.67945 -0.305054)
			(stroke
				(width 0.1)
				(type default)
			)
			(layer "F.Fab")
		)
		(fp_line
			(start -0.12065 -0.305054)
			(end -0.12065 -0.2794)
			(stroke
				(width 0.1)
				(type default)
			)
			(layer "F.Fab")
		)
		(fp_line
			(start -0.12065 -0.2794)
			(end 0.12065 -0.2794)
			(stroke
				(width 0.1)
				(type default)
			)
			(layer "F.Fab")
		)
		(fp_line
			(start -0.12065 0.2794)
			(end -0.12065 0.3048)
			(stroke
				(width 0.1)
				(type default)
			)
			(layer "F.Fab")
		)
		(fp_line
			(start -0.12065 0.3048)
			(end -0.67945 0.3048)
			(stroke
				(width 0.1)
				(type default)
			)
			(layer "F.Fab")
		)
		(fp_line
			(start 0.120396 0.2794)
			(end -0.12065 0.2794)
			(stroke
				(width 0.1)
				(type default)
			)
			(layer "F.Fab")
		)
		(fp_line
			(start 0.120396 0.3048)
			(end 0.120396 0.2794)
			(stroke
				(width 0.1)
				(type default)
			)
			(layer "F.Fab")
		)
		(fp_line
			(start 0.12065 -0.3048)
			(end 0.67945 -0.3048)
			(stroke
				(width 0.1)
				(type default)
			)
			(layer "F.Fab")
		)
		(fp_line
			(start 0.12065 -0.2794)
			(end 0.12065 -0.3048)
			(stroke
				(width 0.1)
				(type default)
			)
			(layer "F.Fab")
		)
		(fp_line
			(start 0.67945 -0.3048)
			(end 0.67945 0.3048)
			(stroke
				(width 0.1)
				(type default)
			)
			(layer "F.Fab")
		)
		(fp_line
			(start 0.67945 0.3048)
			(end 0.120396 0.3048)
			(stroke
				(width 0.1)
				(type default)
			)
			(layer "F.Fab")
		)
		(pad "1" smd circle
			(at -0.40005 0)
			(size 0 0)
			(layers "F.Cu" "F.Mask" "F.Paste")
			(net "P1V5_BAT_IN")
		)
		(pad "2" smd circle
			(at 0.40005 0)
			(size 0 0)
			(layers "F.Cu" "F.Mask" "F.Paste")
			(net "GND")
		)
	)
	(footprint ""
		(layer "F.Cu")
		(at 284.73654 -403.961092 -90)
		(property "Reference" "R2624"
			(at 0 0 270)
			(layer "F.SilkS")
			(hide yes)
			(effects
				(font
					(size 1.27 1.27)
				)
			)
		)
		(property "Value" ""
			(at 0 0 270)
			(layer "F.Fab")
			(effects
				(font
					(size 1.27 1.27)
				)
			)
		)
		(duplicate_pad_numbers_are_jumpers no)
		(fp_line
			(start -0.7874 0.4064)
			(end -0.7874 -0.4064)
			(stroke
				(width 0.1524)
				(type default)
			)
			(layer "F.SilkS")
		)
		(fp_line
			(start 0.7874 0.4064)
			(end -0.7874 0.4064)
			(stroke
				(width 0.1524)
				(type default)
			)
			(layer "F.SilkS")
		)
		(fp_line
			(start -0.7874 -0.4064)
			(end 0.7874 -0.4064)
			(stroke
				(width 0.1524)
				(type default)
			)
			(layer "F.SilkS")
		)
		(fp_line
			(start 0.7874 -0.4064)
			(end 0.7874 0.4064)
			(stroke
				(width 0.1524)
				(type default)
			)
			(layer "F.SilkS")
		)
		(fp_line
			(start -0.67945 0.3048)
			(end -0.67945 -0.305054)
			(stroke
				(width 0.1)
				(type default)
			)
			(layer "F.Fab")
		)
		(fp_line
			(start -0.12065 0.3048)
			(end -0.67945 0.3048)
			(stroke
				(width 0.1)
				(type default)
			)
			(layer "F.Fab")
		)
		(fp_line
			(start 0.120396 0.3048)
			(end 0.120396 0.2794)
			(stroke
				(width 0.1)
				(type default)
			)
			(layer "F.Fab")
		)
		(fp_line
			(start 0.67945 0.3048)
			(end 0.120396 0.3048)
			(stroke
				(width 0.1)
				(type default)
			)
			(layer "F.Fab")
		)
		(fp_line
			(start -0.12065 0.2794)
			(end -0.12065 0.3048)
			(stroke
				(width 0.1)
				(type default)
			)
			(layer "F.Fab")
		)
		(fp_line
			(start 0.120396 0.2794)
			(end -0.12065 0.2794)
			(stroke
				(width 0.1)
				(type default)
			)
			(layer "F.Fab")
		)
		(fp_line
			(start -0.12065 -0.2794)
			(end 0.12065 -0.2794)
			(stroke
				(width 0.1)
				(type default)
			)
			(layer "F.Fab")
		)
		(fp_line
			(start 0.12065 -0.2794)
			(end 0.12065 -0.3048)
			(stroke
				(width 0.1)
				(type default)
			)
			(layer "F.Fab")
		)
		(fp_line
			(start 0.12065 -0.3048)
			(end 0.67945 -0.3048)
			(stroke
				(width 0.1)
				(type default)
			)
			(layer "F.Fab")
		)
		(fp_line
			(start 0.67945 -0.3048)
			(end 0.67945 0.3048)
			(stroke
				(width 0.1)
				(type default)
			)
			(layer "F.Fab")
		)
		(fp_line
			(start -0.67945 -0.305054)
			(end -0.12065 -0.305054)
			(stroke
				(width 0.1)
				(type default)
			)
			(layer "F.Fab")
		)
		(fp_line
			(start -0.12065 -0.305054)
			(end -0.12065 -0.2794)
			(stroke
				(width 0.1)
				(type default)
			)
			(layer "F.Fab")
		)
		(pad "1" smd circle
			(at -0.40005 0 270)
			(size 0 0)
			(layers "F.Cu" "F.Mask" "F.Paste")
			(net "P12V_HSC_TEMP_E")
		)
		(pad "2" smd circle
			(at 0.40005 0 270)
			(size 0 0)
			(layers "F.Cu" "F.Mask" "F.Paste")
			(net "P12V_HSC_TEMP_D-")
		)
	)
	(footprint ""
		(layer "F.Cu")
		(at 22.479 -364.617 180)
		(property "Reference" "C5020"
			(at 0 0 180)
			(layer "F.SilkS")
			(hide yes)
			(effects
				(font
					(size 1.27 1.27)
				)
			)
		)
		(property "Value" ""
			(at 0 0 180)
			(layer "F.Fab")
			(effects
				(font
					(size 1.27 1.27)
				)
			)
		)
		(duplicate_pad_numbers_are_jumpers no)
		(fp_line
			(start 0.7874 0.4064)
			(end -0.7874 0.4064)
			(stroke
				(width 0.1524)
				(type default)
			)
			(layer "F.SilkS")
		)
		(fp_line
			(start 0.7874 -0.4064)
			(end 0.7874 0.4064)
			(stroke
				(width 0.1524)
				(type default)
			)
			(layer "F.SilkS")
		)
		(fp_line
			(start -0.7874 0.4064)
			(end -0.7874 -0.4064)
			(stroke
				(width 0.1524)
				(type default)
			)
			(layer "F.SilkS")
		)
		(fp_line
			(start -0.7874 -0.4064)
			(end 0.7874 -0.4064)
			(stroke
				(width 0.1524)
				(type default)
			)
			(layer "F.SilkS")
		)
		(fp_line
			(start 0.67945 0.3048)
			(end 0.120396 0.3048)
			(stroke
				(width 0.1)
				(type default)
			)
			(layer "F.Fab")
		)
		(fp_line
			(start 0.67945 -0.3048)
			(end 0.67945 0.3048)
			(stroke
				(width 0.1)
				(type default)
			)
			(layer "F.Fab")
		)
		(fp_line
			(start 0.12065 -0.2794)
			(end 0.12065 -0.3048)
			(stroke
				(width 0.1)
				(type default)
			)
			(layer "F.Fab")
		)
		(fp_line
			(start 0.12065 -0.3048)
			(end 0.67945 -0.3048)
			(stroke
				(width 0.1)
				(type default)
			)
			(layer "F.Fab")
		)
		(fp_line
			(start 0.120396 0.3048)
			(end 0.120396 0.2794)
			(stroke
				(width 0.1)
				(type default)
			)
			(layer "F.Fab")
		)
		(fp_line
			(start 0.120396 0.2794)
			(end -0.12065 0.2794)
			(stroke
				(width 0.1)
				(type default)
			)
			(layer "F.Fab")
		)
		(fp_line
			(start -0.12065 0.3048)
			(end -0.67945 0.3048)
			(stroke
				(width 0.1)
				(type default)
			)
			(layer "F.Fab")
		)
		(fp_line
			(start -0.12065 0.2794)
			(end -0.12065 0.3048)
			(stroke
				(width 0.1)
				(type default)
			)
			(layer "F.Fab")
		)
		(fp_line
			(start -0.12065 -0.2794)
			(end 0.12065 -0.2794)
			(stroke
				(width 0.1)
				(type default)
			)
			(layer "F.Fab")
		)
		(fp_line
			(start -0.12065 -0.305054)
			(end -0.12065 -0.2794)
			(stroke
				(width 0.1)
				(type default)
			)
			(layer "F.Fab")
		)
		(fp_line
			(start -0.67945 0.3048)
			(end -0.67945 -0.305054)
			(stroke
				(width 0.1)
				(type default)
			)
			(layer "F.Fab")
		)
		(fp_line
			(start -0.67945 -0.305054)
			(end -0.12065 -0.305054)
			(stroke
				(width 0.1)
				(type default)
			)
			(layer "F.Fab")
		)
		(pad "1" smd circle
			(at -0.40005 0 180)
			(size 0 0)
			(layers "F.Cu" "F.Mask" "F.Paste")
			(net "GND")
		)
		(pad "2" smd circle
			(at 0.40005 0 180)
			(size 0 0)
			(layers "F.Cu" "F.Mask" "F.Paste")
			(net "PVDDCR_CPU1_P1_SMB_ALERT")
		)
	)
	(footprint ""
		(layer "F.Cu")
		(at 180.970936 -133.235954 -90)
		(property "Reference" "R217"
			(at 0 0 270)
			(layer "F.SilkS")
			(hide yes)
			(effects
				(font
					(size 1.27 1.27)
				)
			)
		)
		(property "Value" ""
			(at 0 0 270)
			(layer "F.Fab")
			(effects
				(font
					(size 1.27 1.27)
				)
			)
		)
		(duplicate_pad_numbers_are_jumpers no)
		(fp_line
			(start -0.7874 0.4064)
			(end -0.7874 -0.4064)
			(stroke
				(width 0.1524)
				(type default)
			)
			(layer "F.SilkS")
		)
		(fp_line
			(start 0.7874 0.4064)
			(end -0.7874 0.4064)
			(stroke
				(width 0.1524)
				(type default)
			)
			(layer "F.SilkS")
		)
		(fp_line
			(start -0.7874 -0.4064)
			(end 0.7874 -0.4064)
			(stroke
				(width 0.1524)
				(type default)
			)
			(layer "F.SilkS")
		)
		(fp_line
			(start 0.7874 -0.4064)
			(end 0.7874 0.4064)
			(stroke
				(width 0.1524)
				(type default)
			)
			(layer "F.SilkS")
		)
		(fp_line
			(start -0.67945 0.3048)
			(end -0.67945 -0.305054)
			(stroke
				(width 0.1)
				(type default)
			)
			(layer "F.Fab")
		)
		(fp_line
			(start -0.12065 0.3048)
			(end -0.67945 0.3048)
			(stroke
				(width 0.1)
				(type default)
			)
			(layer "F.Fab")
		)
		(fp_line
			(start 0.120396 0.3048)
			(end 0.120396 0.2794)
			(stroke
				(width 0.1)
				(type default)
			)
			(layer "F.Fab")
		)
		(fp_line
			(start 0.67945 0.3048)
			(end 0.120396 0.3048)
			(stroke
				(width 0.1)
				(type default)
			)
			(layer "F.Fab")
		)
		(fp_line
			(start -0.12065 0.2794)
			(end -0.12065 0.3048)
			(stroke
				(width 0.1)
				(type default)
			)
			(layer "F.Fab")
		)
		(fp_line
			(start 0.120396 0.2794)
			(end -0.12065 0.2794)
			(stroke
				(width 0.1)
				(type default)
			)
			(layer "F.Fab")
		)
		(fp_line
			(start -0.12065 -0.2794)
			(end 0.12065 -0.2794)
			(stroke
				(width 0.1)
				(type default)
			)
			(layer "F.Fab")
		)
		(fp_line
			(start 0.12065 -0.2794)
			(end 0.12065 -0.3048)
			(stroke
				(width 0.1)
				(type default)
			)
			(layer "F.Fab")
		)
		(fp_line
			(start 0.12065 -0.3048)
			(end 0.67945 -0.3048)
			(stroke
				(width 0.1)
				(type default)
			)
			(layer "F.Fab")
		)
		(fp_line
			(start 0.67945 -0.3048)
			(end 0.67945 0.3048)
			(stroke
				(width 0.1)
				(type default)
			)
			(layer "F.Fab")
		)
		(fp_line
			(start -0.67945 -0.305054)
			(end -0.12065 -0.305054)
			(stroke
				(width 0.1)
				(type default)
			)
			(layer "F.Fab")
		)
		(fp_line
			(start -0.12065 -0.305054)
			(end -0.12065 -0.2794)
			(stroke
				(width 0.1)
				(type default)
			)
			(layer "F.Fab")
		)
		(pad "1" smd circle
			(at -0.40005 0 270)
			(size 0 0)
			(layers "F.Cu" "F.Mask" "F.Paste")
			(net "RST_CPU0_RSMRST_N")
		)
		(pad "2" smd circle
			(at 0.40005 0 270)
			(size 0 0)
			(layers "F.Cu" "F.Mask" "F.Paste")
			(net "FM_CPU0_RSMRST_N")
		)
	)
	(footprint ""
		(layer "F.Cu")
		(at 77.55001 -24.713946 -90)
		(property "Reference" "PR3830"
			(at 0 0 270)
			(layer "F.SilkS")
			(hide yes)
			(effects
				(font
					(size 1.27 1.27)
				)
			)
		)
		(property "Value" ""
			(at 0 0 270)
			(layer "F.Fab")
			(effects
				(font
					(size 1.27 1.27)
				)
			)
		)
		(duplicate_pad_numbers_are_jumpers no)
		(fp_line
			(start -0.7874 0.4064)
			(end -0.7874 -0.4064)
			(stroke
				(width 0.1524)
				(type default)
			)
			(layer "F.SilkS")
		)
		(fp_line
			(start 0.7874 0.4064)
			(end -0.7874 0.4064)
			(stroke
				(width 0.1524)
				(type default)
			)
			(layer "F.SilkS")
		)
		(fp_line
			(start -0.7874 -0.4064)
			(end 0.7874 -0.4064)
			(stroke
				(width 0.1524)
				(type default)
			)
			(layer "F.SilkS")
		)
		(fp_line
			(start 0.7874 -0.4064)
			(end 0.7874 0.4064)
			(stroke
				(width 0.1524)
				(type default)
			)
			(layer "F.SilkS")
		)
		(fp_line
			(start -0.67945 0.3048)
			(end -0.67945 -0.305054)
			(stroke
				(width 0.1)
				(type default)
			)
			(layer "F.Fab")
		)
		(fp_line
			(start -0.12065 0.3048)
			(end -0.67945 0.3048)
			(stroke
				(width 0.1)
				(type default)
			)
			(layer "F.Fab")
		)
		(fp_line
			(start 0.120396 0.3048)
			(end 0.120396 0.2794)
			(stroke
				(width 0.1)
				(type default)
			)
			(layer "F.Fab")
		)
		(fp_line
			(start 0.67945 0.3048)
			(end 0.120396 0.3048)
			(stroke
				(width 0.1)
				(type default)
			)
			(layer "F.Fab")
		)
		(fp_line
			(start -0.12065 0.2794)
			(end -0.12065 0.3048)
			(stroke
				(width 0.1)
				(type default)
			)
			(layer "F.Fab")
		)
		(fp_line
			(start 0.120396 0.2794)
			(end -0.12065 0.2794)
			(stroke
				(width 0.1)
				(type default)
			)
			(layer "F.Fab")
		)
		(fp_line
			(start -0.12065 -0.2794)
			(end 0.12065 -0.2794)
			(stroke
				(width 0.1)
				(type default)
			)
			(layer "F.Fab")
		)
		(fp_line
			(start 0.12065 -0.2794)
			(end 0.12065 -0.3048)
			(stroke
				(width 0.1)
				(type default)
			)
			(layer "F.Fab")
		)
		(fp_line
			(start 0.12065 -0.3048)
			(end 0.67945 -0.3048)
			(stroke
				(width 0.1)
				(type default)
			)
			(layer "F.Fab")
		)
		(fp_line
			(start 0.67945 -0.3048)
			(end 0.67945 0.3048)
			(stroke
				(width 0.1)
				(type default)
			)
			(layer "F.Fab")
		)
		(fp_line
			(start -0.67945 -0.305054)
			(end -0.12065 -0.305054)
			(stroke
				(width 0.1)
				(type default)
			)
			(layer "F.Fab")
		)
		(fp_line
			(start -0.12065 -0.305054)
			(end -0.12065 -0.2794)
			(stroke
				(width 0.1)
				(type default)
			)
			(layer "F.Fab")
		)
		(pad "1" smd circle
			(at -0.40005 0 270)
			(size 0 0)
			(layers "F.Cu" "F.Mask" "F.Paste")
			(net "P12V_AUX")
		)
		(pad "2" smd circle
			(at 0.40005 0 270)
			(size 0 0)
			(layers "F.Cu" "F.Mask" "F.Paste")
			(net "P12V_OCP_VCC_2")
		)
	)
)
